(kicad_pcb
	(version 20260206)
	(generator "pcbnew")
	(generator_version "10.0")
	(general
		(thickness 1.6)
		(legacy_teardrops no)
	)
	(paper "A4")
	(title_block
		(title "Bryce Canyon_Front Panel_16369-1_OCP.brd")
		(comment 1 "Bryce Canyon / footprints 36-37 of 154")
	)
	(layers
		(0 "F.Cu" signal "TOP")
		(4 "In1.Cu" signal "L2GND")
		(6 "In2.Cu" signal "L3VCC")
		(2 "B.Cu" signal "BOTTOM")
		(9 "F.Adhes" user "F.Adhesive")
		(11 "B.Adhes" user "B.Adhesive")
		(13 "F.Paste" user "Package Geometry/Pastemask Top")
		(15 "B.Paste" user "Package Geometry/Pastemask Bottom")
		(5 "F.SilkS" user "Ref Des/Silkscreen Top")
		(7 "B.SilkS" user "Ref Des/Silkscreen Bottom")
		(1 "F.Mask" user "Board Geometry/Soldermask Top")
		(3 "B.Mask" user "Board Geometry/Soldermask Bottom")
		(17 "Dwgs.User" user "User.Drawings")
		(19 "Cmts.User" user "User.Comments")
		(21 "Eco1.User" user "User.Eco1")
		(23 "Eco2.User" user "User.Eco2")
		(25 "Edge.Cuts" user "Board Geometry/Outline")
		(27 "Margin" user)
		(31 "F.CrtYd" user "Package Geometry/Place Bound Top")
		(29 "B.CrtYd" user "Package Geometry/Place Bound Bottom")
		(35 "F.Fab" user "Ref Des/Assembly Top")
		(33 "B.Fab" user "Ref Des/Assembly Bottom")
	)
	(footprint ""
		(layer "F.Cu")
		(at 29.550106 -1.299972 180)
		(property "Reference" "CN1"
			(at 0 0 180)
			(layer "F.SilkS")
			(hide yes)
			(effects
				(font
					(size 1.27 1.27)
				)
			)
		)
		(property "Value" "SKT-SAS15P-14P-81-GP"
			(at -24.4729 -9.8044 180)
			(unlocked yes)
			(layer "F.Fab")
			(hide yes)
			(effects
				(font
					(size 1.016 1.016)
					(thickness 0.1524)
				)
			)
		)
		(property "Device Type" "SASM2130081TR"
			(at -24.4729 -11.3284 180)
			(unlocked yes)
			(layer "F.Fab")
			(hide yes)
			(effects
				(font
					(size 1.016 1.016)
					(thickness 0.1524)
				)
			)
		)
		(duplicate_pad_numbers_are_jumpers no)
		(fp_line
			(start 25.0698 1.4478)
			(end -25.0698 1.4478)
			(stroke
				(width 0.1524)
				(type default)
			)
			(layer "F.SilkS")
		)
		(fp_line
			(start 25.0698 -7.999984)
			(end 25.0698 1.4478)
			(stroke
				(width 0.1524)
				(type default)
			)
			(layer "F.SilkS")
		)
		(fp_line
			(start 22.165056 -7.999984)
			(end 25.0698 -7.999984)
			(stroke
				(width 0.1524)
				(type default)
			)
			(layer "F.SilkS")
		)
		(fp_line
			(start 21.66493 -1.500124)
			(end 21.66493 -7.500112)
			(stroke
				(width 0.1524)
				(type default)
			)
			(layer "F.SilkS")
		)
		(fp_line
			(start 15.5448 1.5367)
			(end 16.3068 1.5367)
			(stroke
				(width 0.3302)
				(type default)
			)
			(layer "F.SilkS")
		)
		(fp_line
			(start -21.165058 -0.999998)
			(end 21.165058 -0.999998)
			(stroke
				(width 0.1524)
				(type default)
			)
			(layer "F.SilkS")
		)
		(fp_line
			(start -21.66493 -7.500112)
			(end -21.66493 -1.500124)
			(stroke
				(width 0.1524)
				(type default)
			)
			(layer "F.SilkS")
		)
		(fp_line
			(start -25.0698 1.4478)
			(end -25.0698 -7.999984)
			(stroke
				(width 0.1524)
				(type default)
			)
			(layer "F.SilkS")
		)
		(fp_line
			(start -25.0698 -7.999984)
			(end -22.165056 -7.999984)
			(stroke
				(width 0.1524)
				(type default)
			)
			(layer "F.SilkS")
		)
		(fp_arc
			(start 21.66493 -1.500124)
			(mid 21.518607 -1.146515)
			(end 21.165058 -0.999998)
			(stroke
				(width 0.1524)
				(type default)
			)
			(layer "F.SilkS")
		)
		(fp_arc
			(start 21.66493 -7.500112)
			(mid 21.811503 -7.85359)
			(end 22.165056 -7.999984)
			(stroke
				(width 0.1524)
				(type default)
			)
			(layer "F.SilkS")
		)
		(fp_arc
			(start -21.165058 -0.999998)
			(mid -21.518635 -1.146484)
			(end -21.66493 -1.500124)
			(stroke
				(width 0.1524)
				(type default)
			)
			(layer "F.SilkS")
		)
		(fp_arc
			(start -22.165056 -7.999984)
			(mid -21.811503 -7.85359)
			(end -21.66493 -7.500112)
			(stroke
				(width 0.1524)
				(type default)
			)
			(layer "F.SilkS")
		)
		(fp_poly
			(pts
				(xy 15.957804 1.403096) (xy 15.322804 2.038096) (xy 16.592804 2.038096)
			)
			(stroke
				(width 0)
				(type default)
			)
			(fill yes)
			(layer "F.SilkS")
		)
		(fp_rect
			(start -24.4983 1.1938)
			(end 24.4983 -8.001)
			(stroke
				(width 0)
				(type default)
			)
			(fill no)
			(layer "F.CrtYd")
		)
		(fp_poly
			(pts
				(xy -25.3238 1.7018) (xy -25.3238 -8.509) (xy 25.3238 -8.509) (xy 25.3238 -0.00635) (xy 24.4983 -0.00635)
				(xy 24.4983 -8.001) (xy -24.4983 -8.001) (xy -24.4983 1.1938) (xy 24.4983 1.1938) (xy 24.4983 0.00635)
				(xy 25.3238 0.00635) (xy 25.3238 1.7018)
			)
			(stroke
				(width 0)
				(type default)
			)
			(fill no)
			(layer "F.CrtYd")
		)
		(fp_rect
			(start -25.3238 1.7018)
			(end 25.3238 -8.509)
			(stroke
				(width 0)
				(type default)
			)
			(fill no)
			(layer "F.Fab")
		)
		(fp_text user "Slit"
			(at 3.214878 -3.280918 180)
			(unlocked yes)
			(layer "F.SilkS")
			(effects
				(font
					(size 1.016 1.016)
					(thickness 0.1524)
				)
				(justify left)
			)
		)
		(pad "" np_thru_hole circle
			(at -18.945098 0 180)
			(size 0.254 0.254)
			(drill 1.3208)
			(layers "*.Cu" "*.Mask")
			(clearance 0.889)
			(thermal_gap 0.889)
		)
		(pad "" np_thru_hole circle
			(at 18.945098 0 180)
			(size 0.254 0.254)
			(drill 1.3208)
			(layers "*.Cu" "*.Mask")
			(clearance 0.889)
			(thermal_gap 0.889)
		)
		(pad "G1" smd rect
			(at 23.515066 -1.75006 180)
			(size 2.5908 3.4036)
			(layers "F.Cu" "F.Mask" "F.Paste")
			(net "GND")
		)
		(pad "G2" smd rect
			(at -23.515066 -1.75006 180)
			(size 2.5908 3.4036)
			(layers "F.Cu" "F.Mask" "F.Paste")
			(net "GND")
		)
		(pad "P1" smd rect
			(at 1.905 0.299974 180)
			(size 0.6096 1.6002)
			(layers "F.Cu" "F.Mask" "F.Paste")
			(net "P5V_USB_A")
		)
		(pad "P2" smd rect
			(at 0.635 0.299974 180)
			(size 0.6096 1.6002)
			(layers "F.Cu" "F.Mask" "F.Paste")
			(net "P5V_USB_B")
		)
		(pad "P3" smd rect
			(at -0.635 0.299974 180)
			(size 0.6096 1.6002)
			(layers "F.Cu" "F.Mask" "F.Paste")
			(net "FAULT_LED_B")
		)
		(pad "P4" smd rect
			(at -1.905 0.299974 180)
			(size 0.6096 1.6002)
			(layers "F.Cu" "F.Mask" "F.Paste")
			(net "PWR_LED_B_N")
		)
		(pad "P5" smd rect
			(at -3.175 0.299974 180)
			(size 0.6096 1.6002)
			(layers "F.Cu" "F.Mask" "F.Paste")
			(net "P3V3_STBY_B")
		)
		(pad "P6" smd rect
			(at -4.445 0.299974 180)
			(size 0.6096 1.6002)
			(layers "F.Cu" "F.Mask" "F.Paste")
			(net "SYS_RESET_BTN_B_N")
		)
		(pad "P7" smd rect
			(at -5.715 0.299974 180)
			(size 0.6096 1.6002)
			(layers "F.Cu" "F.Mask" "F.Paste")
			(net "GND")
		)
		(pad "P8" smd rect
			(at -6.985 0.299974 180)
			(size 0.6096 1.6002)
			(layers "F.Cu" "F.Mask" "F.Paste")
			(net "I2C_DPB_B_SCL")
		)
		(pad "P9" smd rect
			(at -8.255 0.299974 180)
			(size 0.6096 1.6002)
			(layers "F.Cu" "F.Mask" "F.Paste")
			(net "I2C_DPB_B_SDA")
		)
		(pad "P10" smd rect
			(at -9.525 0.299974 180)
			(size 0.6096 1.6002)
			(layers "F.Cu" "F.Mask" "F.Paste")
			(net "PWR_BTN_B")
		)
		(pad "P11" smd rect
			(at -10.795 0.299974 180)
			(size 0.6096 1.6002)
			(layers "F.Cu" "F.Mask" "F.Paste")
			(net "UART_IOC_B_TX")
		)
		(pad "P12" smd rect
			(at -12.065 0.299974 180)
			(size 0.6096 1.6002)
			(layers "F.Cu" "F.Mask" "F.Paste")
			(net "UART_IOC_B_RX")
		)
		(pad "P13" smd rect
			(at -13.335 0.299974 180)
			(size 0.6096 1.6002)
			(layers "F.Cu" "F.Mask" "F.Paste")
			(net "GND")
		)
		(pad "P14" smd rect
			(at -14.605 0.299974 180)
			(size 0.6096 1.6002)
			(layers "F.Cu" "F.Mask" "F.Paste")
			(net "UART_EXP_B_TX")
		)
		(pad "P15" smd rect
			(at -15.875 0.299974 180)
			(size 0.6096 1.6002)
			(layers "F.Cu" "F.Mask" "F.Paste")
			(net "UART_EXP_B_RX")
		)
		(pad "S1" smd rect
			(at 15.88008 0.299974 180)
			(size 0.6096 1.6002)
			(layers "F.Cu" "F.Mask" "F.Paste")
			(net "UART_EXP_A_TX")
		)
		(pad "S2" smd rect
			(at 14.61008 0.299974 180)
			(size 0.6096 1.6002)
			(layers "F.Cu" "F.Mask" "F.Paste")
			(net "UART_EXP_A_RX")
		)
		(pad "S3" smd rect
			(at 13.34008 0.299974 180)
			(size 0.6096 1.6002)
			(layers "F.Cu" "F.Mask" "F.Paste")
			(net "GND")
		)
		(pad "S4" smd rect
			(at 12.07008 0.299974 180)
			(size 0.6096 1.6002)
			(layers "F.Cu" "F.Mask" "F.Paste")
			(net "UART_IOC_A_TX")
		)
		(pad "S5" smd rect
			(at 10.80008 0.299974 180)
			(size 0.6096 1.6002)
			(layers "F.Cu" "F.Mask" "F.Paste")
			(net "UART_IOC_A_RX")
		)
		(pad "S6" smd rect
			(at 9.53008 0.299974 180)
			(size 0.6096 1.6002)
			(layers "F.Cu" "F.Mask" "F.Paste")
			(net "GND")
		)
		(pad "S7" smd rect
			(at 8.26008 0.299974 180)
			(size 0.6096 1.6002)
			(layers "F.Cu" "F.Mask" "F.Paste")
			(net "PWR_BTN_A")
		)
		(pad "S8" smd rect
			(at 7.480046 0.299974 180)
			(size 0.508 1.6002)
			(layers "F.Cu" "F.Mask" "F.Paste")
			(net "I2C_DPB_A_SCL")
		)
		(pad "S9" smd rect
			(at 6.679946 0.299974 180)
			(size 0.508 1.6002)
			(layers "F.Cu" "F.Mask" "F.Paste")
			(net "I2C_DPB_A_SDA")
		)
		(pad "S10" smd rect
			(at 5.8801 0.299974 180)
			(size 0.508 1.6002)
			(layers "F.Cu" "F.Mask" "F.Paste")
			(net "SYS_RESET_BTN_A_N")
		)
		(pad "S11" smd rect
			(at 5.08 0.299974 180)
			(size 0.508 1.6002)
			(layers "F.Cu" "F.Mask" "F.Paste")
			(net "P3V3_STBY_A")
		)
		(pad "S12" smd rect
			(at 4.2799 0.299974 180)
			(size 0.508 1.6002)
			(layers "F.Cu" "F.Mask" "F.Paste")
			(net "PWR_LED_A_N")
		)
		(pad "S13" smd rect
			(at 3.480054 0.299974 180)
			(size 0.508 1.6002)
			(layers "F.Cu" "F.Mask" "F.Paste")
			(net "FAULT_LED_A")
		)
		(pad "S14" smd rect
			(at 2.679954 0.299974 180)
			(size 0.508 1.6002)
			(layers "F.Cu" "F.Mask" "F.Paste")
			(net "Net_27")
		)
		(zone
			(layers "F.Cu" "B.Cu" "In1.Cu" "In2.Cu")
			(hatch none 0.5)
			(connect_pads
				(clearance 0)
			)
			(min_thickness 0.25)
			(keepout
				(tracks not_allowed)
				(vias allowed)
				(pads allowed)
				(copperpour not_allowed)
				(footprints allowed)
			)
			(placement
				(enabled no)
				(sheetname "")
			)
			(fill
				(thermal_gap 0.5)
				(thermal_bridge_width 0.5)
				(island_removal_mode 0)
			)
			(polygon
				(pts
					(arc
						(start 11.570208 -1.299972)
						(mid 9.639808 -1.299972)
						(end 11.570208 -1.299972)
					)
				)
			)
		)
		(zone
			(layers "F.Cu" "B.Cu" "In1.Cu" "In2.Cu")
			(hatch none 0.5)
			(connect_pads
				(clearance 0)
			)
			(min_thickness 0.25)
			(keepout
				(tracks not_allowed)
				(vias allowed)
				(pads allowed)
				(copperpour not_allowed)
				(footprints allowed)
			)
			(placement
				(enabled no)
				(sheetname "")
			)
			(fill
				(thermal_gap 0.5)
				(thermal_bridge_width 0.5)
				(island_removal_mode 0)
			)
			(polygon
				(pts
					(arc
						(start 49.460404 -1.299972)
						(mid 47.530004 -1.299972)
						(end 49.460404 -1.299972)
					)
				)
			)
		)
	)
	(footprint ""
		(layer "F.Cu")
		(at 47.9806 -29.3878 90)
		(property "Reference" "D10"
			(at 0 0 90)
			(layer "F.SilkS")
			(hide yes)
			(effects
				(font
					(size 1.27 1.27)
				)
			)
		)
		(property "Value" "PESD5V0X1UAB-GP"
			(at 0 -4.690618 90)
			(unlocked yes)
			(layer "F.Fab")
			(hide yes)
			(effects
				(font
					(size 1.016 1.016)
					(thickness 0.1524)
				)
			)
		)
		(property "Device Type" "SOD523AKH26"
			(at 0 -6.214618 90)
			(unlocked yes)
			(layer "F.Fab")
			(hide yes)
			(effects
				(font
					(size 1.016 1.016)
					(thickness 0.1524)
				)
			)
		)
		(duplicate_pad_numbers_are_jumpers no)
		(fp_line
			(start 0.5334 -1.4478)
			(end 0.5334 1.524)
			(stroke
				(width 0.1524)
				(type default)
			)
			(layer "F.SilkS")
		)
		(fp_line
			(start -0.5334 -1.4478)
			(end 0.5334 -1.4478)
			(stroke
				(width 0.1524)
				(type default)
			)
			(layer "F.SilkS")
		)
		(fp_line
			(start 0.5334 1.524)
			(end -0.5334 1.524)
			(stroke
				(width 0.1524)
				(type default)
			)
			(layer "F.SilkS")
		)
		(fp_line
			(start -0.5334 1.524)
			(end -0.5334 -1.4478)
			(stroke
				(width 0.1524)
				(type default)
			)
			(layer "F.SilkS")
		)
		(fp_line
			(start 0.4064 1.651)
			(end -0.4064 1.651)
			(stroke
				(width 0.4064)
				(type default)
			)
			(layer "F.SilkS")
		)
		(fp_rect
			(start -0.6096 1.8542)
			(end 0.6096 -1.524)
			(stroke
				(width 0)
				(type default)
			)
			(fill no)
			(layer "F.CrtYd")
		)
		(fp_poly
			(pts
				(xy -0.6096 -1.524) (xy 0.6096 -1.524) (xy 0.6096 1.8542) (xy -0.6096 1.8542)
			)
			(stroke
				(width 0)
				(type default)
			)
			(fill no)
			(layer "F.Fab")
		)
		(pad "A" smd rect
			(at 0 -0.762 90)
			(size 0.5588 1.016)
			(layers "F.Cu" "F.Mask" "F.Paste")
			(net "GND")
		)
		(pad "K" smd rect
			(at 0 0.762 90)
			(size 0.5588 1.016)
			(layers "F.Cu" "F.Mask" "F.Paste")
			(net "SYS_RESET_BTN_B")
		)
	)
)
